# Stackup_F0T_FIO_4L_1p6mm_IT-170GT_RTF_Rev0p1_20211105.xls — Stackup (pcb-stackup)
| STACKUP |  |  |  | Target Z (ohms) - MicroStrip |  |  |  |  | 50 | Breakout | 85 |  | Breakout |  |
|  |  |  |  | Target Z (ohms) - StripLine |  |  |  |  | 50 |  | 85 |  |  |  |
|  |  |  |  | Z tolerance |  |  |  |  | 0.1 |  | 0.1 |  |  |  |
|  |  |  |  | Z Type |  |  |  |  | Single | Single | Differential |  | Differential |  |
| Layer# | Material | Description |  | Copper Weight (oz) | Thickness (mil) | Tolerance (mil) | Glass Fabric | Er | Width | Width | Width | Space | Width | Space |
|  |  |  | Soldermask |  | 0.6 |  |  | 3.8 |  |  |  |  |  |  |
| 1 |  |  | TOP | 0.5+plating | 1.95 |  |  |  | 7.4 | 4 | 5.8 | 4.2 | 3.9 | 4 |
|  | IT-170GT |  | PP |  | 4 | ±0.709 | 2116x1 | 3.87 |  |  |  |  |  |  |
| 2 |  |  | GND | 1 (RTF) | 1.3 |  |  |  |  |  |  |  |  |  |
|  | IT-170GT |  | CORE |  | 47.3 | ±5.12 | Vendor Define | 4.17 |  |  |  |  |  |  |
| 3 |  |  | GND1 | 1 (RTF) | 1.3 |  |  |  |  |  |  |  |  |  |
|  | IT-170GT |  | PP |  | 4 | ±0.709 | 2116x1 | 3.87 |  |  |  |  |  |  |
| 4 |  |  | BOTTOM | 0.5+plating | 1.95 |  |  |  | 7.4 | 4 | 5.8 | 4.2 | 3.9 | 4 |
|  |  |  | Soldermask |  | 0.6 |  |  | 3.8 |  |  |  |  |  |  |
|  |  |  |  | Total | 63 | ±10% |  |  |  |  |  |  |  |  |
